(kicad_pcb
	(version 20241229)
	(generator "pcbnew")
	(generator_version "9.0")
	(general
		(thickness 1.62)
		(legacy_teardrops no)
	)
	(paper "A3")
	(title_block
		(title "COM Express 7 Baseboard")
		(date "2025-02-04")
		(rev "1.1.2")
		(company "Antmicro Ltd")
		(comment 1 "www.antmicro.com")
		(comment 9 "footprints 421-425 of 802")
	)
	(layers
		(0 "F.Cu" signal)
		(4 "In1.Cu" signal)
		(6 "In2.Cu" signal)
		(8 "In3.Cu" signal)
		(10 "In4.Cu" signal)
		(12 "In5.Cu" signal)
		(14 "In6.Cu" signal)
		(2 "B.Cu" signal)
		(9 "F.Adhes" user "F.Adhesive")
		(11 "B.Adhes" user "B.Adhesive")
		(13 "F.Paste" user)
		(15 "B.Paste" user)
		(5 "F.SilkS" user "F.Silkscreen")
		(7 "B.SilkS" user "B.Silkscreen")
		(1 "F.Mask" user)
		(3 "B.Mask" user)
		(17 "Dwgs.User" user "User.Drawings")
		(19 "Cmts.User" user "User.Comments")
		(21 "Eco1.User" user "User.Eco1")
		(23 "Eco2.User" user "User.Eco2")
		(25 "Edge.Cuts" user)
		(27 "Margin" user)
		(31 "F.CrtYd" user "F.Courtyard")
		(29 "B.CrtYd" user "B.Courtyard")
		(35 "F.Fab" user)
		(33 "B.Fab" user)
	)
	(footprint "antmicro-footprints:Choke_0805_2012Metric"
		(layer "F.Cu")
		(at 127.25 109.42 180)
		(property "Reference" "T3"
			(at 1.6 -1.85 0)
			(unlocked yes)
			(layer "F.SilkS")
			(effects
				(font
					(size 0.7 0.7)
					(thickness 0.15)
				)
				(justify left bottom)
			)
		)
		(property "Value" "Choke_SRF2012A-801Y"
			(at 0 -7 180)
			(unlocked yes)
			(layer "F.Fab")
			(effects
				(font
					(size 0.7 0.7)
					(thickness 0.15)
				)
				(justify left bottom)
			)
		)
		(property "Datasheet" "https://www.bourns.com/docs/product-datasheets/srf2012a-801y.pdf"
			(at 0 0 180)
			(layer "F.Fab")
			(hide yes)
			(effects
				(font
					(size 1.27 1.27)
					(thickness 0.15)
				)
			)
		)
		(property "Author" "Antmicro"
			(at 254.5 218.84 0)
			(layer "F.Fab")
			(hide yes)
			(effects
				(font
					(size 1 1)
					(thickness 0.15)
				)
			)
		)
		(property "IMax" "0.3 A"
			(at 254.5 218.84 0)
			(layer "F.Fab")
			(hide yes)
			(effects
				(font
					(size 1 1)
					(thickness 0.15)
				)
			)
		)
		(property "License" "Apache-2.0"
			(at 254.5 218.84 0)
			(layer "F.Fab")
			(hide yes)
			(effects
				(font
					(size 1 1)
					(thickness 0.15)
				)
			)
		)
		(property "MPN" "SRF2012A-801Y"
			(at 254.5 218.84 0)
			(layer "F.Fab")
			(hide yes)
			(effects
				(font
					(size 1 1)
					(thickness 0.15)
				)
			)
		)
		(property "Manufacturer" "Bourns"
			(at 254.5 218.84 0)
			(layer "F.Fab")
			(hide yes)
			(effects
				(font
					(size 1 1)
					(thickness 0.15)
				)
			)
		)
		(property "Public" "False"
			(at 254.5 218.84 0)
			(layer "F.Fab")
			(hide yes)
			(effects
				(font
					(size 1 1)
					(thickness 0.15)
				)
			)
		)
		(property ki_fp_filters "IND_ACM9070_TDK")
		(sheetname "2xUSB3.0+RJ45")
		(sheetfile "usb3+rj45.kicad_sch")
		(attr smd)
		(fp_rect
			(start -1.5 -0.9)
			(end 1.5 0.9)
			(stroke
				(width 0.05)
				(type solid)
			)
			(fill no)
			(layer "F.CrtYd")
		)
		(pad "1" smd roundrect
			(at -0.96 -0.46 180)
			(size 0.675 0.475)
			(layers "F.Cu" "F.Mask" "F.Paste")
			(roundrect_rratio 0.25)
			(net 693 "/2xUSB3.0+RJ45/DC_FL+")
			(pinfunction "1")
			(pintype "passive")
			(teardrops
				(best_length_ratio 0.2)
				(max_length 1)
				(best_width_ratio 0.9)
				(max_width 2)
				(curved_edges yes)
				(filter_ratio 0.9)
				(enabled yes)
				(allow_two_segments yes)
				(prefer_zone_connections yes)
			)
		)
		(pad "2" smd roundrect
			(at 0.96 -0.46 180)
			(size 0.675 0.475)
			(layers "F.Cu" "F.Mask" "F.Paste")
			(roundrect_rratio 0.25)
			(net 149 "/2xUSB3.0+RJ45/DC+")
			(pinfunction "2")
			(pintype "passive")
			(teardrops
				(best_length_ratio 0.2)
				(max_length 1)
				(best_width_ratio 0.9)
				(max_width 2)
				(curved_edges yes)
				(filter_ratio 0.9)
				(enabled yes)
				(allow_two_segments yes)
				(prefer_zone_connections yes)
			)
		)
		(pad "3" smd roundrect
			(at 0.96 0.46 180)
			(size 0.675 0.475)
			(layers "F.Cu" "F.Mask" "F.Paste")
			(roundrect_rratio 0.25)
			(net 150 "/2xUSB3.0+RJ45/DC-")
			(pinfunction "3")
			(pintype "passive")
			(teardrops
				(best_length_ratio 0.2)
				(max_length 1)
				(best_width_ratio 0.9)
				(max_width 2)
				(curved_edges yes)
				(filter_ratio 0.9)
				(enabled yes)
				(allow_two_segments yes)
				(prefer_zone_connections yes)
			)
		)
		(pad "4" smd roundrect
			(at -0.96 0.46 180)
			(size 0.675 0.475)
			(layers "F.Cu" "F.Mask" "F.Paste")
			(roundrect_rratio 0.25)
			(net 694 "/2xUSB3.0+RJ45/DC_FL-")
			(pinfunction "4")
			(pintype "passive")
			(teardrops
				(best_length_ratio 0.2)
				(max_length 1)
				(best_width_ratio 0.9)
				(max_width 2)
				(curved_edges yes)
				(filter_ratio 0.9)
				(enabled yes)
				(allow_two_segments yes)
				(prefer_zone_connections yes)
			)
		)
	)
	(footprint "antmicro-footprints:TP_SMD_0.75mm"
		(layer "F.Cu")
		(at 130.39 129.56)
		(property "Reference" "TP88"
			(at 0.46 -1.25 90)
			(layer "F.SilkS")
			(effects
				(font
					(size 0.7 0.7)
					(thickness 0.15)
				)
				(justify left bottom)
			)
		)
		(property "Value" "TP_0.75mm_SMD"
			(at 0 1.2 0)
			(layer "F.Fab")
			(effects
				(font
					(size 0.7 0.7)
					(thickness 0.15)
				)
				(justify left bottom)
			)
		)
		(property "Author" "Antmicro"
			(at 0 0 0)
			(layer "F.Fab")
			(hide yes)
			(effects
				(font
					(size 1 1)
					(thickness 0.15)
				)
			)
		)
		(property "License" "Apache-2.0"
			(at 0 0 0)
			(layer "F.Fab")
			(hide yes)
			(effects
				(font
					(size 1 1)
					(thickness 0.15)
				)
			)
		)
		(property "MPN" ""
			(at 0 0 0)
			(layer "F.Fab")
			(hide yes)
			(effects
				(font
					(size 1 1)
					(thickness 0.15)
				)
			)
		)
		(property "Manufacturer" ""
			(at 0 0 0)
			(layer "F.Fab")
			(hide yes)
			(effects
				(font
					(size 1 1)
					(thickness 0.15)
				)
			)
		)
		(property "Public" "False"
			(at 0 0 0)
			(layer "F.Fab")
			(hide yes)
			(effects
				(font
					(size 1 1)
					(thickness 0.15)
				)
			)
		)
		(sheetname "KR to SFI #2")
		(sheetfile "kr_sfi.kicad_sch")
		(attr exclude_from_pos_files exclude_from_bom)
		(fp_circle
			(center 0 0)
			(end 0.475 0)
			(stroke
				(width 0.05)
				(type default)
			)
			(fill no)
			(layer "F.CrtYd")
		)
		(pad "1" smd circle
			(at 0 0)
			(size 0.75 0.75)
			(layers "F.Cu" "F.Mask")
			(net 751 "Net-(U45C-CLKOUTA-)")
			(pinfunction "1")
			(pintype "passive")
			(teardrops
				(best_length_ratio 0.4)
				(max_length 1)
				(best_width_ratio 0.9)
				(max_width 2)
				(curved_edges yes)
				(filter_ratio 0.9)
				(enabled yes)
				(allow_two_segments yes)
				(prefer_zone_connections yes)
			)
		)
	)
	(footprint "antmicro-footprints:R_0402_1005Metric"
		(layer "F.Cu")
		(at 143.45 84.06)
		(descr "Resistor SMD 0402")
		(tags "resistor SMD 0402")
		(property "Reference" "R132"
			(at -3.7 0.45 0)
			(layer "F.SilkS")
			(effects
				(font
					(size 0.7 0.7)
					(thickness 0.15)
				)
				(justify left bottom)
			)
		)
		(property "Value" "R_0R_0402"
			(at -1.011843 1.772047 0)
			(layer "F.Fab")
			(effects
				(font
					(size 0.7 0.7)
					(thickness 0.15)
				)
				(justify left bottom)
			)
		)
		(property "Datasheet" "https://industrial.panasonic.com/cdbs/www-data/pdf/RDA0000/AOA0000C301.pdf"
			(at 0 0 0)
			(layer "F.Fab")
			(hide yes)
			(effects
				(font
					(size 1.27 1.27)
					(thickness 0.15)
				)
			)
		)
		(property "Author" "Antmicro"
			(at 0 0 0)
			(layer "F.Fab")
			(hide yes)
			(effects
				(font
					(size 1 1)
					(thickness 0.15)
				)
			)
		)
		(property "Current" "1A"
			(at 0 0 0)
			(layer "F.Fab")
			(hide yes)
			(effects
				(font
					(size 1 1)
					(thickness 0.15)
				)
			)
		)
		(property "License" "Apache-2.0"
			(at 0 0 0)
			(layer "F.Fab")
			(hide yes)
			(effects
				(font
					(size 1 1)
					(thickness 0.15)
				)
			)
		)
		(property "MPN" "ERJ2GE0R00X"
			(at 0 0 0)
			(layer "F.Fab")
			(hide yes)
			(effects
				(font
					(size 1 1)
					(thickness 0.15)
				)
			)
		)
		(property "Manufacturer" "Panasonic"
			(at 0 0 0)
			(layer "F.Fab")
			(hide yes)
			(effects
				(font
					(size 1 1)
					(thickness 0.15)
				)
			)
		)
		(property "Public" "False"
			(at 0 0 0)
			(layer "F.Fab")
			(hide yes)
			(effects
				(font
					(size 1 1)
					(thickness 0.15)
				)
			)
		)
		(property "Tolerance" ""
			(at 0 0 0)
			(layer "F.Fab")
			(hide yes)
			(effects
				(font
					(size 1 1)
					(thickness 0.15)
				)
			)
		)
		(property "Val" "0R"
			(at 0 0 0)
			(layer "F.Fab")
			(hide yes)
			(effects
				(font
					(size 1 1)
					(thickness 0.15)
				)
			)
		)
		(sheetname "M.2 key E")
		(sheetfile "m2keye.kicad_sch")
		(attr smd)
		(fp_rect
			(start -0.925 -0.47)
			(end 0.925 0.47)
			(stroke
				(width 0.05)
				(type default)
			)
			(fill no)
			(layer "F.CrtYd")
		)
		(fp_rect
			(start -0.5 -0.25)
			(end 0.5 0.25)
			(stroke
				(width 0.15)
				(type solid)
			)
			(fill no)
			(layer "F.Fab")
		)
		(pad "1" smd roundrect
			(at -0.48 0)
			(size 0.59 0.64)
			(layers "F.Cu" "F.Mask" "F.Paste")
			(roundrect_rratio 0.25)
			(net 528 "/Backplane/~{PERST}")
			(pintype "passive")
			(teardrops
				(best_length_ratio 0.2)
				(max_length 1)
				(best_width_ratio 0.9)
				(max_width 2)
				(curved_edges yes)
				(filter_ratio 0.9)
				(enabled yes)
				(allow_two_segments yes)
				(prefer_zone_connections yes)
			)
		)
		(pad "2" smd roundrect
			(at 0.48 0)
			(size 0.59 0.64)
			(layers "F.Cu" "F.Mask" "F.Paste")
			(roundrect_rratio 0.25)
			(net 23 "/M.2 key E/~{PERST_D}")
			(pintype "passive")
			(teardrops
				(best_length_ratio 0.2)
				(max_length 1)
				(best_width_ratio 0.9)
				(max_width 2)
				(curved_edges yes)
				(filter_ratio 0.9)
				(enabled yes)
				(allow_two_segments yes)
				(prefer_zone_connections yes)
			)
		)
	)
	(footprint "antmicro-footprints:R_0402_1005Metric"
		(layer "F.Cu")
		(at 134.425 84.310001)
		(descr "Resistor SMD 0402")
		(tags "resistor SMD 0402")
		(property "Reference" "R231"
			(at 0.775 0.449999 0)
			(layer "F.SilkS")
			(effects
				(font
					(size 0.7 0.7)
					(thickness 0.15)
				)
				(justify left bottom)
			)
		)
		(property "Value" "R_0R_0402"
			(at -1.011843 1.772047 0)
			(layer "F.Fab")
			(effects
				(font
					(size 0.7 0.7)
					(thickness 0.15)
				)
				(justify left bottom)
			)
		)
		(property "Datasheet" "https://industrial.panasonic.com/cdbs/www-data/pdf/RDA0000/AOA0000C301.pdf"
			(at 0 0 0)
			(layer "F.Fab")
			(hide yes)
			(effects
				(font
					(size 1.27 1.27)
					(thickness 0.15)
				)
			)
		)
		(property "Author" "Antmicro"
			(at 0 0 0)
			(layer "F.Fab")
			(hide yes)
			(effects
				(font
					(size 1 1)
					(thickness 0.15)
				)
			)
		)
		(property "Current" "1A"
			(at 0 0 0)
			(layer "F.Fab")
			(hide yes)
			(effects
				(font
					(size 1 1)
					(thickness 0.15)
				)
			)
		)
		(property "License" "Apache-2.0"
			(at 0 0 0)
			(layer "F.Fab")
			(hide yes)
			(effects
				(font
					(size 1 1)
					(thickness 0.15)
				)
			)
		)
		(property "MPN" "ERJ2GE0R00X"
			(at 0 0 0)
			(layer "F.Fab")
			(hide yes)
			(effects
				(font
					(size 1 1)
					(thickness 0.15)
				)
			)
		)
		(property "Manufacturer" "Panasonic"
			(at 0 0 0)
			(layer "F.Fab")
			(hide yes)
			(effects
				(font
					(size 1 1)
					(thickness 0.15)
				)
			)
		)
		(property "Public" "False"
			(at 0 0 0)
			(layer "F.Fab")
			(hide yes)
			(effects
				(font
					(size 1 1)
					(thickness 0.15)
				)
			)
		)
		(property "Tolerance" ""
			(at 0 0 0)
			(layer "F.Fab")
			(hide yes)
			(effects
				(font
					(size 1 1)
					(thickness 0.15)
				)
			)
		)
		(property "Val" "0R"
			(at 0 0 0)
			(layer "F.Fab")
			(hide yes)
			(effects
				(font
					(size 1 1)
					(thickness 0.15)
				)
			)
		)
		(sheetname "GPIO expander")
		(sheetfile "gpio_exp.kicad_sch")
		(attr smd dnp)
		(fp_rect
			(start -0.925 -0.47)
			(end 0.925 0.47)
			(stroke
				(width 0.05)
				(type default)
			)
			(fill no)
			(layer "F.CrtYd")
		)
		(fp_rect
			(start -0.5 -0.25)
			(end 0.5 0.25)
			(stroke
				(width 0.15)
				(type solid)
			)
			(fill no)
			(layer "F.Fab")
		)
		(pad "1" smd roundrect
			(at -0.48 0)
			(size 0.59 0.64)
			(layers "F.Cu" "F.Mask" "F.Paste")
			(roundrect_rratio 0.25)
			(net 633 "Net-(U41-A0)")
			(pintype "passive")
			(teardrops
				(best_length_ratio 0.2)
				(max_length 1)
				(best_width_ratio 0.9)
				(max_width 2)
				(curved_edges yes)
				(filter_ratio 0.9)
				(enabled yes)
				(allow_two_segments yes)
				(prefer_zone_connections yes)
			)
		)
		(pad "2" smd roundrect
			(at 0.48 0)
			(size 0.59 0.64)
			(layers "F.Cu" "F.Mask" "F.Paste")
			(roundrect_rratio 0.25)
			(net 2 "+3V3")
			(pintype "passive")
			(teardrops
				(best_length_ratio 0.2)
				(max_length 1)
				(best_width_ratio 0.9)
				(max_width 2)
				(curved_edges yes)
				(filter_ratio 0.9)
				(enabled yes)
				(allow_two_segments yes)
				(prefer_zone_connections yes)
			)
		)
	)
	(footprint "antmicro-footprints:TP_SMD_0.75mm"
		(layer "F.Cu")
		(at 138.85 128.71)
		(property "Reference" "TP90"
			(at 0.5 -3.3 90)
			(layer "F.SilkS")
			(effects
				(font
					(size 0.7 0.7)
					(thickness 0.15)
				)
				(justify left bottom)
			)
		)
		(property "Value" "TP_0.75mm_SMD"
			(at 0 1.2 0)
			(layer "F.Fab")
			(effects
				(font
					(size 0.7 0.7)
					(thickness 0.15)
				)
				(justify left bottom)
			)
		)
		(property "Author" "Antmicro"
			(at 0 0 0)
			(layer "F.Fab")
			(hide yes)
			(effects
				(font
					(size 1 1)
					(thickness 0.15)
				)
			)
		)
		(property "License" "Apache-2.0"
			(at 0 0 0)
			(layer "F.Fab")
			(hide yes)
			(effects
				(font
					(size 1 1)
					(thickness 0.15)
				)
			)
		)
		(property "MPN" ""
			(at 0 0 0)
			(layer "F.Fab")
			(hide yes)
			(effects
				(font
					(size 1 1)
					(thickness 0.15)
				)
			)
		)
		(property "Manufacturer" ""
			(at 0 0 0)
			(layer "F.Fab")
			(hide yes)
			(effects
				(font
					(size 1 1)
					(thickness 0.15)
				)
			)
		)
		(property "Public" "False"
			(at 0 0 0)
			(layer "F.Fab")
			(hide yes)
			(effects
				(font
					(size 1 1)
					(thickness 0.15)
				)
			)
		)
		(sheetname "KR to SFI #2")
		(sheetfile "kr_sfi.kicad_sch")
		(attr exclude_from_pos_files exclude_from_bom)
		(fp_circle
			(center 0 0)
			(end 0.475 0)
			(stroke
				(width 0.05)
				(type default)
			)
			(fill no)
			(layer "F.CrtYd")
		)
		(pad "1" smd circle
			(at 0 0)
			(size 0.75 0.75)
			(layers "F.Cu" "F.Mask")
			(net 753 "Net-(U45C-CLKOUTB-)")
			(pinfunction "1")
			(pintype "passive")
			(teardrops
				(best_length_ratio 0.4)
				(max_length 1)
				(best_width_ratio 0.9)
				(max_width 2)
				(curved_edges yes)
				(filter_ratio 0.9)
				(enabled yes)
				(allow_two_segments yes)
				(prefer_zone_connections yes)
			)
		)
	)
)
